FILE_TYPE = MULTI_PHYS_TABLE;

PART 'Q_XTAL_4P_13BI_24GND'

{========================================================================================}
:VALUE      | PART_TYPE | MATERIAL | PART_NUMBER       = STANDARD        | LIFECYCLE      | PART_NUMBER       | JEDEC_TYPE                     | ALT_SYMBOLS | DESCRIPTION                                | MANUFTR | MANUF_PN                               | RD_CMPLS_LVL | CMPLS_LVL | CLASS | DIP_SMD | FROM_PJ          | DATA                                           | FP_ECN           | EE_CHECK_LIST | STATUS | PSL | PREFERENCE | CREATOR | CREATEDAY  ;
{========================================================================================}
 '25MHZ'    | 'SMLF'    | 'MISC'   | 'BG625000030'(!)  = ''              | ''             | 'BG625000030'     |'X_7MXA'| ''          | 'XTAL SMD 25MHZ(+-30PPM,16PF)7M25000034'   | 'TXC'   | '7M25000034'                           | 'EP(V1)'     | 'EP(V1)'  | 'IO'  | ''      | 'T2H-GAVEN'      | 'TXC_7M25000034_REVA7.pdf'                     | ''               | ''            | ''     | ''  | ''         | ''      | '20141020'
 '25MHZ'    | 'SMLF'    | 'EMPTY'  | 'BG625000030'(!)  = ''              | ''             | 'BG625000030'     |'X_7MXA'| ''          | 'XTAL SMD 25MHZ(+-30PPM,16PF)7M25000034'   | 'TXC'   | '7M25000034'                           | 'EP(V1)'     | 'EP(V1)'  | 'IO'  | ''      | 'T2H-GAVEN'      | 'TXC_7M25000034_REVA7.pdf'                     | ''               | ''            | ''     | ''  | ''         | ''      | '20141020'
 '48MHZ'    | 'SMLF'    | 'MISC'   | 'BG648000003'(!)  = ''              | ''             | 'BG648000003'     |'X_7MXA'| ''          | 'XTAL SMD 48MHZ(15PPM,8PF)7M48000176'      | 'TXC'   | '7M48000176'                           | 'EP(V1)'     | 'EP(V1)'  | 'IO'  | ''      | 'T2H-GAVEN'      | 'TXC_7M48000176_REVA5.pdf'                     | ''               | ''            | ''     | ''  | ''         | ''      | '20141020'
 '48MHZ'    | 'SMLF'    | 'EMPTY'  | 'BG648000003'(!)  = ''              | ''             | 'BG648000003'     |'X_7MXA'| ''          | 'XTAL SMD 48MHZ(15PPM,8PF)7M48000176'      | 'TXC'   | '7M48000176'                           | 'EP(V1)'     | 'EP(V1)'  | 'IO'  | ''      | 'T2H-GAVEN'      | 'TXC_7M48000176_REVA5.pdf'                     | ''               | ''            | ''     | ''  | ''         | ''      | '20141020'
 '48MHZ'    | 'SMLF'    | 'MISC'   | 'BG648000039'(!)  = ''              | ''             | 'BG648000039'     |'X_7MXA'| ''          | 'XTAL SMD 48MHZ(30PPM,10PF)7M48020003'     | 'TXC'   | '7M48020003'                           | 'EP(V1)'     | ''        | 'IO'  | ''      | 'S6A-MEALY'      | 'TXC_7M48020003_REVS1.pdf'                     | ''               | ''            | ''     | ''  | ''         | ''      | '20141103'
 '48MHZ'    | 'SMLF'    | 'EMPTY'  | 'BG648000039'(!)  = ''              | ''             | 'BG648000039'     |'X_7MXA'| ''          | 'XTAL SMD 48MHZ(30PPM,10PF)7M48020003'     | 'TXC'   | '7M48020003'                           | 'EP(V1)'     | ''        | 'IO'  | ''      | 'S6A-MEALY'      | 'TXC_7M48020003_REVS1.pdf'                     | ''               | ''            | ''     | ''  | ''         | ''      | '20141103'
 '40MHZ'    | 'SMLF'    | 'MISC'   | 'BG640000005'(!)  = ''              | ''             | 'BG640000005'     |'X_4S_8Y40000010_2X1-6'| ''          | 'CRYSTAL 40MHZ(+-10PPM,8PF)8Y40000010'     | 'TXC'   | '8Y40000010'                           | 'EP(V1)'     | 'EP(V1)'  | 'IO'  | ''      | 'T2H-GAVEN'      | 'TXC_8Y40000010_REVS1.pdf'                     | ''               | ''            | ''     | ''  | ''         | ''      | '20141201'
 '40MHZ'    | 'SMLF'    | 'EMPTY'  | 'BG640000005'(!)  = ''              | ''             | 'BG640000005'     |'X_4S_8Y40000010_2X1-6'| ''          | 'CRYSTAL 40MHZ(+-10PPM,8PF)8Y40000010'     | 'TXC'   | '8Y40000010'                           | 'EP(V1)'     | 'EP(V1)'  | 'IO'  | ''      | 'T2H-GAVEN'      | 'TXC_8Y40000010_REVS1.pdf'                     | ''               | ''            | ''     | ''  | ''         | ''      | '20141201'
 '24MHZ'    | 'SMLF'    | 'MISC'   | 'BG624000101'(!)  = ''              | ''             | 'BG624000101'     |'X_7MXA'| ''          | 'XTAL SMD 24MHZ(+-30PPM,18PF)7M24020002'   | 'TXC'   | '7M24020002'                           | 'EP(V1)'     | ''        | 'IO'  | ''      | 'S3A-THOMAS'     | 'TXC_7M24020002_REVA1.pdf'                     | ''               | ''            | ''     | ''  | ''         | ''      | '20141230'
 '24MHZ'    | 'SMLF'    | 'EMPTY'  | 'BG624000101'(!)  = ''              | ''             | 'BG624000101'     |'X_7MXA'| ''          | 'XTAL SMD 24MHZ(+-30PPM,18PF)7M24020002'   | 'TXC'   | '7M24020002'                           | 'EP(V1)'     | ''        | 'IO'  | ''      | 'S3A-THOMAS'     | 'TXC_7M24020002_REVA1.pdf'                     | ''               | ''            | ''     | ''  | ''         | ''      | '20141230'
 '25MHZ'    | 'SMLF'    | 'MISC'   | 'BG625000802'(!)  = ''              | ''             | 'BG625000802'     |'X_7MXA'| ''          | 'XTAL SMD 25MHZ(+-20PPM,20PF)7M25020008'   | 'TXC'   | '7M25020008'                           | 'EP(V1)'     | 'EP(V1)'  | 'IO'  | ''      | 'S5M-GLEN'       | 'TXC_7M25020008_REVA1.pdf'                     | ''               | ''            | ''     | ''  | ''         | ''      | '20150112'
 '25MHZ'    | 'SMLF'    | 'EMPTY'  | 'BG625000802'(!)  = ''              | ''             | 'BG625000802'     |'X_7MXA'| ''          | 'XTAL SMD 25MHZ(+-20PPM,20PF)7M25020008'   | 'TXC'   | '7M25020008'                           | 'EP(V1)'     | 'EP(V1)'  | 'IO'  | ''      | 'S5M-GLEN'       | 'TXC_7M25020008_REVA1.pdf'                     | ''               | ''            | ''     | ''  | ''         | ''      | '20150112'
 '25MHZ'    | 'SMLF'    | 'MISC'   | 'BG625000037'(!)  = ''              | ''             | 'BG625000037'     |'OSC4_E3FB'| ''          | 'XTAL SMD25MHZ(10PF,20PPM) Q22FA238004990' | 'SEG'   | 'Q22FA2380049900'                      | 'EU'         | 'EU'      | 'IO'  | ''      | 'F20A-CHAN-DER'  | 'SEG_Q22FA2380049900.pdf'                      | ''               | ''            | ''     | ''  | ''         | ''      | '20150706'
 '25MHZ'    | 'SMLF'    | 'EMPTY'  | 'BG625000037'(!)  = ''              | ''             | 'BG625000037'     |'OSC4_E3FB'| ''          | 'XTAL SMD25MHZ(10PF,20PPM) Q22FA238004990' | 'SEG'   | 'Q22FA2380049900'                      | 'EU'         | 'EU'      | 'IO'  | ''      | 'F20A-CHAN-DER'  | 'SEG_Q22FA2380049900.pdf'                      | ''               | ''            | ''     | ''  | ''         | ''      | '20150706'
 '33.33MHZ' | 'SMLF'    | 'MISC'   | 'BG633330000'(!)  = ''              | ''             | 'BG633330000'     |'X_7MXA'| ''          | 'XTAL SMD 33.33MHZ(12PF,20PPM)7M33300004'  | 'TXC'   | '7M33300004'                           | 'EP(V1)'     | ''        | 'IO'  | ''      | 'S5B-ROSSI'      | 'TXC_7M33300004.pdf'                           | ''               | ''            | ''     | ''  | ''         | ''      | '20151126'
 '33.33MHZ' | 'SMLF'    | 'EMPTY'  | 'BG633330000'(!)  = ''              | ''             | 'BG633330000'     |'X_7MXA'| ''          | 'XTAL SMD 33.33MHZ(12PF,20PPM)7M33300004'  | 'TXC'   | '7M33300004'                           | 'EP(V1)'     | ''        | 'IO'  | ''      | 'S5B-ROSSI'      | 'TXC_7M33300004.pdf'                           | ''               | ''            | ''     | ''  | ''         | ''      | '20151126'
 '12MHZ'    | 'SMLF'    | 'MISC'   | 'BG612000014'(!)  = ''              | ''             | 'BG612000014'     |'OSC4_E3FB'| ''          | 'XTAL 12MHZ(20PPM,10PF)E3SB12.0000F10E22'  | 'HHE'   | 'E3SB12.0000F10E22'                    | 'EP(V1)'     | 'EP(V1)'  | 'IO'  | ''      | 'S2S-LOUISE'     | 'HHE_E3SB12.0000F10E22.pdf'                    | ''               | ''            | ''     | ''  | ''         | ''      | '20151207'
 '12MHZ'    | 'SMLF'    | 'EMPTY'  | 'BG612000014'(!)  = ''              | ''             | 'BG612000014'     |'OSC4_E3FB'| ''          | 'XTAL 12MHZ(20PPM,10PF)E3SB12.0000F10E22'  | 'HHE'   | 'E3SB12.0000F10E22'                    | 'EP(V1)'     | 'EP(V1)'  | 'IO'  | ''      | 'S2S-LOUISE'     | 'HHE_E3SB12.0000F10E22.pdf'                    | ''               | ''            | ''     | ''  | ''         | ''      | '20151207'
 '12MHZ'    | 'SMLF'    | 'MISC'   | 'BG612000107'(!)  = ''              | ''             | 'BG612000107'     |'X_4S_FL4000120_3-2X2-5'| ''          | 'XTAL SMD 12MHZ(12PF,10PPM)AEC'            | 'ERC'   | 'FL1200151Q'                           | 'EP(V1)'     | ''        | 'IO'  | ''      | 'T2HV-RONNY'     | 'ERC_FL1200151Q_verA.pdf'                      | ''               | ''            | ''     | ''  | ''         | ''      | '20151222'
 '12MHZ'    | 'SMLF'    | 'EMPTY'  | 'BG612000107'(!)  = ''              | ''             | 'BG612000107'     |'X_4S_FL4000120_3-2X2-5'| ''          | 'XTAL SMD 12MHZ(12PF,10PPM)AEC'            | 'ERC'   | 'FL1200151Q'                           | 'EP(V1)'     | ''        | 'IO'  | ''      | 'T2HV-RONNY'     | 'ERC_FL1200151Q_verA.pdf'                      | ''               | ''            | ''     | ''  | ''         | ''      | '20151222'
 '25MHZ'    | 'SMLF'    | 'MISC'   | 'BG6250000B9'(!)  = ''              | ''             | 'BG6250000B9'     |'X_4S_FL4000120_3-2X2-5'| ''          | 'XTAL SMD 25MHZ(18PF,20PPM)FL2500333'      | 'ERC'   | 'FL2500333'                            | 'EP(V1)'     | 'EP(V1)'  | 'IO'  | ''      | 'T2HV-RONNY'     | 'ERC_FL2500333.pdf'                            | ''               | ''            | ''     | ''  | ''         | ''      | '20160115'
 '25MHZ'    | 'SMLF'    | 'EMPTY'  | 'BG6250000B9'(!)  = ''              | ''             | 'BG6250000B9'     |'X_4S_FL4000120_3-2X2-5'| ''          | 'XTAL SMD 25MHZ(18PF,20PPM)FL2500333'      | 'ERC'   | 'FL2500333'                            | 'EP(V1)'     | 'EP(V1)'  | 'IO'  | ''      | 'T2HV-RONNY'     | 'ERC_FL2500333.pdf'                            | ''               | ''            | ''     | ''  | ''         | ''      | '20160115'
 '25MHZ'    | 'SMLF'    | 'MISC'   | 'BG625000186'(!)  = ''              | ''             | 'BG625000186'     |'X_4S_FL4000120_3-2X2-5'| ''          | 'XTAL SMD 25MHZ(20PF,20PPM)FL2500157'      | 'ERC'   | 'FL2500157'                            | 'EP(V1)'     | ''        | 'IO'  | ''      | 'T2HV-RONNY'     | 'ERC_FL2500157.pdf'                            | ''               | ''            | ''     | ''  | ''         | ''      | '20160201'
 '25MHZ'    | 'SMLF'    | 'EMPTY'  | 'BG625000186'(!)  = ''              | ''             | 'BG625000186'     |'X_4S_FL4000120_3-2X2-5'| ''          | 'XTAL SMD 25MHZ(20PF,20PPM)FL2500157'      | 'ERC'   | 'FL2500157'                            | 'EP(V1)'     | ''        | 'IO'  | ''      | 'T2HV-RONNY'     | 'ERC_FL2500157.pdf'                            | ''               | ''            | ''     | ''  | ''         | ''      | '20160201'
 '25MHZ'    | 'SMLF'    | 'MISC'   | 'BG625000174'(!)  = ''              | ''             | 'BG625000174'     |'X_4S_FL4000120_3-2X2-5'| ''          | 'XTAL SMD 25MHZ(+-20PPM,20PF)FL2500316Z'   | 'ERC'   | 'FL2500316Z'                           | 'EP(V1)'     | ''        | 'IO'  | ''      | 'F08-MARK'       | 'ERC_FL2500316Z_revA.pdf'                      | ''               | ''            | ''     | ''  | ''         | ''      | '20160203'
 '25MHZ'    | 'SMLF'    | 'EMPTY'  | 'BG625000174'(!)  = ''              | ''             | 'BG625000174'     |'X_4S_FL4000120_3-2X2-5'| ''          | 'XTAL SMD 25MHZ(+-20PPM,20PF)FL2500316Z'   | 'ERC'   | 'FL2500316Z'                           | 'EP(V1)'     | ''        | 'IO'  | ''      | 'F08-MARK'       | 'ERC_FL2500316Z_revA.pdf'                      | ''               | ''            | ''     | ''  | ''         | ''      | '20160203'
 '25MHZ'    | 'SMLF'    | 'MISC'   | 'BG625000322'(!)  = ''              | ''             | 'BG625000322'     |'X_4S_FL4000120_3-2X2-5'| ''          | 'XTAL SMD 25MHZ(18PF,20PPM)AEC'            | 'ERC'   | 'FL2500333Q'                           | 'EP(V1)'     | ''        | 'IO'  | ''      | 'T2HV-TING-HUNG' | 'ERC_FL2500333Q.pdf'                           | ''               | ''            | ''     | ''  | ''         | ''      | '20160302'
 '25MHZ'    | 'SMLF'    | 'EMPTY'  | 'BG625000322'(!)  = ''              | ''             | 'BG625000322'     |'X_4S_FL4000120_3-2X2-5'| ''          | 'XTAL SMD 25MHZ(18PF,20PPM)AEC'            | 'ERC'   | 'FL2500333Q'                           | 'EP(V1)'     | ''        | 'IO'  | ''      | 'T2HV-TING-HUNG' | 'ERC_FL2500333Q.pdf'                           | ''               | ''            | ''     | ''  | ''         | ''      | '20160302'
 '25MHZ'    | 'SMLF'    | 'MISC'   | 'BG625000321'(!)  = ''              | ''             | 'BG625000321'     |'X_4S_FL4000120_3-2X2-5'| ''          | 'XTAL SMD 25MHZ(20PF,20PPM)AEC'            | 'ERC'   | 'FL2500157Q'                           | 'EP(V1)'     | ''        | 'IO'  | ''      | 'T2HV-TING-HUNG' | 'ERC_FL2500157Q.pdf'                           | ''               | ''            | ''     | ''  | ''         | ''      | '20160302'
 '25MHZ'    | 'SMLF'    | 'EMPTY'  | 'BG625000321'(!)  = ''              | ''             | 'BG625000321'     |'X_4S_FL4000120_3-2X2-5'| ''          | 'XTAL SMD 25MHZ(20PF,20PPM)AEC'            | 'ERC'   | 'FL2500157Q'                           | 'EP(V1)'     | ''        | 'IO'  | ''      | 'T2HV-TING-HUNG' | 'ERC_FL2500157Q.pdf'                           | ''               | ''            | ''     | ''  | ''         | ''      | '20160302'
 '25MHZ'    | 'SMLF'    | 'MISC'   | 'BG625000189'(!)  = ''              | ''             | 'BG625000189'     |'X_7MXA'| ''          | 'XTAL SMD 25MHZ(18PF,20PPM)7M25000150'     | 'TXC'   | '7M25000150'                           | 'EP(V1)'     | ''        | 'IO'  | ''      | 'MF2-CHIH-CHIEH' | 'TXC_7M25000150.pdf'                           | ''               | ''            | ''     | ''  | ''         | ''      | '20160307'
 '25MHZ'    | 'SMLF'    | 'EMPTY'  | 'BG625000189'(!)  = ''              | ''             | 'BG625000189'     |'X_7MXA'| ''          | 'XTAL SMD 25MHZ(18PF,20PPM)7M25000150'     | 'TXC'   | '7M25000150'                           | 'EP(V1)'     | ''        | 'IO'  | ''      | 'MF2-CHIH-CHIEH' | 'TXC_7M25000150.pdf'                           | ''               | ''            | ''     | ''  | ''         | ''      | '20160307'
 '12MHZ'    | 'SMLF'    | 'MISC'   | 'BG612000108'(!)  = ''              | ''             | 'BG612000108'     |'X_4S_FL4000120_3-2X2-5'| ''          | 'XTAL SMD 12MHZ(12PF,10PPM)AEC'            | 'ERC'   | 'FL1200179Q'                           | 'EP(V1)'     | ''        | 'IO'  | ''      | 'T2HV-TING-HUNG' | 'ERC_FL1200179Q.pdf'                           | ''               | ''            | ''     | ''  | ''         | ''      | '20160308'
 '12MHZ'    | 'SMLF'    | 'EMPTY'  | 'BG612000108'(!)  = ''              | ''             | 'BG612000108'     |'X_4S_FL4000120_3-2X2-5'| ''          | 'XTAL SMD 12MHZ(12PF,10PPM)AEC'            | 'ERC'   | 'FL1200179Q'                           | 'EP(V1)'     | ''        | 'IO'  | ''      | 'T2HV-TING-HUNG' | 'ERC_FL1200179Q.pdf'                           | ''               | ''            | ''     | ''  | ''         | ''      | '20160308'
 '25MHZ'    | 'SMLF'    | 'MISC'   | 'BG625000195'(!)  = ''              | ''             | 'BG625000195'     |'X_4S_FY2500111'| ''          | 'XTAL SMD 25MHZ(20PF,20PPM)AEC'            | 'ERC'   | 'FY2500133Q'                           | 'EP(V1)'     | ''        | 'IO'  | ''      | 'T2HV-TING-HUNG' | 'ERC_FY2500133Q_VerA.pdf'                      | ''               | ''            | ''     | ''  | ''         | ''      | '20160315'
 '25MHZ'    | 'SMLF'    | 'EMPTY'  | 'BG625000195'(!)  = ''              | ''             | 'BG625000195'     |'X_4S_FY2500111'| ''          | 'XTAL SMD 25MHZ(20PF,20PPM)AEC'            | 'ERC'   | 'FY2500133Q'                           | 'EP(V1)'     | ''        | 'IO'  | ''      | 'T2HV-TING-HUNG' | 'ERC_FY2500133Q_VerA.pdf'                      | ''               | ''            | ''     | ''  | ''         | ''      | '20160315'
 '12MHZ'    | 'SMLF'    | 'MISC'   | 'BG612000109'(!)  = ''              | ''             | 'BG612000109'     |'X_4S_FY2500111'| ''          | 'XTAL SMD 12MHZ(18PF,10PPM)AEC'            | 'ERC'   | 'FY1200112Q'                           | 'EP(V1)'     | ''        | 'IO'  | ''      | 'T2HV-TING-HUNG' | 'ERC_FY1200112Q_VerA.pdf'                      | ''               | ''            | ''     | ''  | ''         | ''      | '20160315'
 '12MHZ'    | 'SMLF'    | 'EMPTY'  | 'BG612000109'(!)  = ''              | ''             | 'BG612000109'     |'X_4S_FY2500111'| ''          | 'XTAL SMD 12MHZ(18PF,10PPM)AEC'            | 'ERC'   | 'FY1200112Q'                           | 'EP(V1)'     | ''        | 'IO'  | ''      | 'T2HV-TING-HUNG' | 'ERC_FY1200112Q_VerA.pdf'                      | ''               | ''            | ''     | ''  | ''         | ''      | '20160315'
 '12MHZ'    | 'SMLF'    | 'MISC'   | 'BG612000023'(!)  = ''              | ''             | 'BG612000023'     |'OSC4_DNCA250000ETS_2-5X2_H26'| ''          | 'XTAL 12MHZ(30PPM,10PF)E2SB12.0000F10E33'  | 'HHE'   | 'E2SB12.0000F10E33'                    | 'EP(V1)'     | 'EP(V1)'  | 'IO'  | ''      | 'S2W-CHIN'       | 'HHE_E2SB12.0000F10E33.pdf'                    | ''               | ''            | ''     | ''  | ''         | ''      | '20160408'
 '12MHZ'    | 'SMLF'    | 'EMPTY'  | 'BG612000023'(!)  = ''              | ''             | 'BG612000023'     |'OSC4_DNCA250000ETS_2-5X2_H26'| ''          | 'XTAL 12MHZ(30PPM,10PF)E2SB12.0000F10E33'  | 'HHE'   | 'E2SB12.0000F10E33'                    | 'EP(V1)'     | 'EP(V1)'  | 'IO'  | ''      | 'S2W-CHIN'       | 'HHE_E2SB12.0000F10E33.pdf'                    | ''               | ''            | ''     | ''  | ''         | ''      | '20160408'
 '25MHZ'    | 'SMLF'    | 'MISC'   | 'BG625000196'(!)  = ''              | ''             | 'BG625000196'     |'X_7MXA'| ''          | 'XTAL SMD 25MHZ(10PF,10PPM)AEC'            | 'TXC'   | 'AM25000002'                           | 'EP(V1)'     | ''        | 'IO'  | ''      | 'T2HV-TING-HUNG' | 'TXC_AM25000002_REVA1.pdf'                     | ''               | ''            | ''     | ''  | ''         | ''      | '20160429'
 '25MHZ'    | 'SMLF'    | 'EMPTY'  | 'BG625000196'(!)  = ''              | ''             | 'BG625000196'     |'X_7MXA'| ''          | 'XTAL SMD 25MHZ(10PF,10PPM)AEC'            | 'TXC'   | 'AM25000002'                           | 'EP(V1)'     | ''        | 'IO'  | ''      | 'T2HV-TING-HUNG' | 'TXC_AM25000002_REVA1.pdf'                     | ''               | ''            | ''     | ''  | ''         | ''      | '20160429'
 '25MHZ'    | 'SMLF'    | 'MISC'   | 'BG625000197'(!)  = ''              | ''             | 'BG625000197'     |'X_7B'| ''          | 'XTAL SMD 25MHZ(16PF,20PPM)AEC'            | 'TXC'   | 'AB25000002'                           | 'EP(V1)'     | ''        | 'IO'  | ''      | 'S2W-CHIN'       | 'TXC_AB25000002_REVA3.pdf'                     | ''               | ''            | ''     | ''  | ''         | ''      | '20160429'
 '25MHZ'    | 'SMLF'    | 'EMPTY'  | 'BG625000197'(!)  = ''              | ''             | 'BG625000197'     |'X_7B'| ''          | 'XTAL SMD 25MHZ(16PF,20PPM)AEC'            | 'TXC'   | 'AB25000002'                           | 'EP(V1)'     | ''        | 'IO'  | ''      | 'S2W-CHIN'       | 'TXC_AB25000002_REVA3.pdf'                     | ''               | ''            | ''     | ''  | ''         | ''      | '20160429'
 '48MHZ'    | 'SMLF'    | 'MISC'   | 'BG648000044'(!)  = ''              | ''             | 'BG648000044'     |'X_7MXA'| ''          | 'XTAL SMD 48MHZ(10PF,30PPM)AEC'            | 'TXC'   | 'AM48000301'                           | 'EP(V1)'     | ''        | 'IO'  | ''      | 'T2HV-TING-HUNG' | 'TXC_AM48000301.pdf'                           | ''               | ''            | ''     | ''  | ''         | ''      | '20160515'
 '48MHZ'    | 'SMLF'    | 'EMPTY'  | 'BG648000044'(!)  = ''              | ''             | 'BG648000044'     |'X_7MXA'| ''          | 'XTAL SMD 48MHZ(10PF,30PPM)AEC'            | 'TXC'   | 'AM48000301'                           | 'EP(V1)'     | ''        | 'IO'  | ''      | 'T2HV-TING-HUNG' | 'TXC_AM48000301.pdf'                           | ''               | ''            | ''     | ''  | ''         | ''      | '20160515'
 '48MHZ'    | 'SMLF'    | 'MISC'   | 'BG648000046'(!)  = ''              | ''             | 'BG648000046'     |'OSC4_E3FB'| ''          | 'XTAL SMD 48MHZ(10PPM,12PF)E3SB48E000801E' | 'HHE'   | 'E3SB48E000801E'                       | 'EP(V1)'     | ''        | 'IO'  | ''      | 'T6MB-JOSEPH'    | 'HHE_E3SB48E000801E.pdf'                       | ''               | ''            | ''     | ''  | ''         | ''      | '20160811'
 '48MHZ'    | 'SMLF'    | 'EMPTY'  | 'BG648000046'(!)  = ''              | ''             | 'BG648000046'     |'OSC4_E3FB'| ''          | 'XTAL SMD 48MHZ(10PPM,12PF)E3SB48E000801E' | 'HHE'   | 'E3SB48E000801E'                       | 'EP(V1)'     | ''        | 'IO'  | ''      | 'T6MB-JOSEPH'    | 'HHE_E3SB48E000801E.pdf'                       | ''               | ''            | ''     | ''  | ''         | ''      | '20160811'
 '25MHZ'    | 'SMLF'    | 'MISC'   | 'BG625000210'(!)  = ''              | ''             | 'BG625000210'     |'X_4S_8Y40000010_2X1-6'| ''          | 'XTAL SMD 25MHZ(20PPM,10PF)8Y25000023'     | 'TXC'   | '8Y25000023'                           | 'EP(V1)'     | ''        | 'IO'  | ''      | 'T2HV-TING-HUNG' | 'TXC_8Y25000023.pdf'                           | ''               | ''            | ''     | ''  | ''         | ''      | '20161020'
 '25MHZ'    | 'SMLF'    | 'EMPTY'  | 'BG625000210'(!)  = ''              | ''             | 'BG625000210'     |'X_4S_8Y40000010_2X1-6'| ''          | 'XTAL SMD 25MHZ(20PPM,10PF)8Y25000023'     | 'TXC'   | '8Y25000023'                           | 'EP(V1)'     | ''        | 'IO'  | ''      | 'T2HV-TING-HUNG' | 'TXC_8Y25000023.pdf'                           | ''               | ''            | ''     | ''  | ''         | ''      | '20161020'
 '25MHZ'    | 'SMLF'    | 'MISC'   | 'BG625000067'(!)  = 'End of Design' | 'End of Life'  | 'BG625000067'     |'X_4S_E5SB25_5X3-2_EOL'| ''          | 'XTAL SMD 25MHZ(+-10PPM,20PF)E5SB25.0000F' | 'HHE'   | 'E5SB25.0000F20D11'                    | 'EP(V1)'     | 'EP(V1)'  | 'IO'  | ''      | 'JBEF-STAN'      | 'HHE_E5SB25.0000F20D11.pdf'                    | ''               | ''            | ''     | ''  | ''         | ''      | '20170606'
 '25MHZ'    | 'SMLF'    | 'EMPTY'  | 'BG625000067'(!)  = 'End of Design' | 'End of Life'  | 'BG625000067'     |'X_4S_E5SB25_5X3-2_EOL'| ''          | 'XTAL SMD 25MHZ(+-10PPM,20PF)E5SB25.0000F' | 'HHE'   | 'E5SB25.0000F20D11'                    | 'EP(V1)'     | 'EP(V1)'  | 'IO'  | ''      | 'JBEF-STAN'      | 'HHE_E5SB25.0000F20D11.pdf'                    | ''               | ''            | ''     | ''  | ''         | ''      | '20170606'
 '24MHZ'    | 'SMLF'    | 'MISC'   | 'BG624000132'(!)  = ''              | ''             | 'BG624000132'     |'X_7MXA'| ''          | 'XTAL SMD 24MHZ(8PF,30PPM)AEC'             | 'TXC'   | 'AM24000304'                           | 'EP(V1)'     | ''        | 'IO'  | ''      | 'T2HV-MARK'      | 'TXC_AM24000304.pdf'                           | ''               | ''            | ''     | ''  | ''         | ''      | '20170914'
 '24MHZ'    | 'SMLF'    | 'EMPTY'  | 'BG624000132'(!)  = ''              | ''             | 'BG624000132'     |'X_7MXA'| ''          | 'XTAL SMD 24MHZ(8PF,30PPM)AEC'             | 'TXC'   | 'AM24000304'                           | 'EP(V1)'     | ''        | 'IO'  | ''      | 'T2HV-MARK'      | 'TXC_AM24000304.pdf'                           | ''               | ''            | ''     | ''  | ''         | ''      | '20170914'
 '25MHZ'    | 'SMLF'    | 'MISC'   | 'BG625000203'(!)  = ''              | ''             | 'BG625000203'     |'X_7MXA'| ''          | 'XTAL SMD 25MHZ (10PPM,10PF)7M25000032'    | 'TXC'   | 'BG625000203'                          | 'EP(V1)'     | ''        | 'IO'  | ''      | 'JG1-TONY'       | 'TXC_7M25000032_revA3.pdf'                     | ''               | ''            | ''     | ''  | ''         | ''      | '20180730'
 '25MHZ'    | 'SMLF'    | 'EMPTY'  | 'BG625000203'(!)  = ''              | ''             | 'BG625000203'     |'X_7MXA'| ''          | 'XTAL SMD 25MHZ (10PPM,10PF)7M25000032'    | 'TXC'   | 'BG625000203'                          | 'EP(V1)'     | ''        | 'IO'  | ''      | 'JG1-TONY'       | 'TXC_7M25000032_revA3.pdf'                     | ''               | ''            | ''     | ''  | ''         | ''      | '20180730'
 '48MHZ'    | 'SMLF'    | 'MISC'   | 'BG648000041'(!)  = ''              | ''             | 'BG648000041'     |'X_4S_FL4000120_3-2X2-5'| ''          | 'XTAL SMD 48MHZ(10PPM,10PF)FL4800070'      | 'ERC'   | 'FL4800070'                            | 'EP(V1)'     | 'EP(V1)'  | 'IO'  | ''      | 'T2N-FRANK'      | 'ERC_FL4800070.pdf'                            | ''               | ''            | ''     | ''  | ''         | ''      | '20181002'
 '48MHZ'    | 'SMLF'    | 'EMPTY'  | 'BG648000041'(!)  = ''              | ''             | 'BG648000041'     |'X_4S_FL4000120_3-2X2-5'| ''          | 'XTAL SMD 48MHZ(10PPM,10PF)FL4800070'      | 'ERC'   | 'FL4800070'                            | 'EP(V1)'     | 'EP(V1)'  | 'IO'  | ''      | 'T2N-FRANK'      | 'ERC_FL4800070.pdf'                            | ''               | ''            | ''     | ''  | ''         | ''      | '20181002'
 '50MHZ'    | 'SMLF'    | 'MISC'   | 'BG650000012'(!)  = ''              | ''             | 'BG650000012'     |'OSC4_E3FB'| ''          | 'XTAL 50MHZ(19PF,+-15PPM) Q22FA2380181100' | 'SEG'   | 'Q22FA2380181100'                      | 'EP(V1)'     | 'EP(V1)'  | 'IO'  | ''      | 'S3A-KENG-HAUR'  | 'SEG_Q22FA2380181100.pdf'                      | ''               | ''            | ''     | ''  | ''         | ''      | '20181023'
 '50MHZ'    | 'SMLF'    | 'EMPTY'  | 'BG650000012'(!)  = ''              | ''             | 'BG650000012'     |'OSC4_E3FB'| ''          | 'XTAL 50MHZ(19PF,+-15PPM) Q22FA2380181100' | 'SEG'   | 'Q22FA2380181100'                      | 'EP(V1)'     | 'EP(V1)'  | 'IO'  | ''      | 'S3A-KENG-HAUR'  | 'SEG_Q22FA2380181100.pdf'                      | ''               | ''            | ''     | ''  | ''         | ''      | '20181023'
 '48MHZ'    | 'SMLF'    | 'MISC '  | 'BG648000055'(!)  = ''              | ''             | 'BG648000055'     |'X_4S_FL4000120_3-2X2-5'| ''          | 'XTAL SMD 48MHZ(10PPM,12PF)FL4800076'      | 'ERC'   | 'FL4800076'                            | 'EU(V1)'     | 'EU(V1)'  | 'IO'  | ''      | 'T6UA-HANK'      | 'ERC_FL4800076.pdf'                            | ''               | ''            | ''     | ''  | ''         | ''      | '20181024'
 '48MHZ'    | 'SMLF'    | 'EMPTY'  | 'BG648000055'(!)  = ''              | ''             | 'BG648000055'     |'X_4S_FL4000120_3-2X2-5'| ''          | 'XTAL SMD 48MHZ(10PPM,12PF)FL4800076'      | 'ERC'   | 'FL4800076'                            | 'EU(V1)'     | 'EU(V1)'  | 'IO'  | ''      | 'T6UA-HANK'      | 'ERC_FL4800076.pdf'                            | ''               | ''            | ''     | ''  | ''         | ''      | '20181024'
 '48MHZ'    | 'SMLF'    | 'MISC'   | 'BG648000073'(!)  = ''              | ''             | 'BG648000073'     |'X_7MXA'| ''          | 'XTAL SMD 48MHZ (12PF,10PPM)7M48000030'    | 'TXC'   | '7M48000030'                           | 'EP(V1)'     | ''        | 'IO'  | ''      | 'F0G-BELL'       | 'TXC_7M48000030.pdf'                           | ''               | ''            | ''     | ''  | ''         | ''      | '20191017'
 '48MHZ'    | 'SMLF'    | 'EMPTY'  | 'BG648000073'(!)  = ''              | ''             | 'BG648000073'     |'X_7MXA'| ''          | 'XTAL SMD 48MHZ (12PF,10PPM)7M48000030'    | 'TXC'   | '7M48000030'                           | 'EP(V1)'     | ''        | 'IO'  | ''      | 'F0G-BELL'       | 'TXC_7M48000030.pdf'                           | ''               | ''            | ''     | ''  | ''         | ''      | '20191017'
 '25MHZ'    | 'SMLF'    | 'MISC'   | 'BG6250000E0'(!)  = ''              | ''             | 'BG6250000E0'     |'X_7MXA'| ''          | 'XTAL SMD 25MHZ (20PF,10PPM)7M25000038'    | 'TXC'   | '7M25000038'                           | 'EP(V1)'     | ''        | 'IO'  | ''      | 'F0G-BELL'       | 'TXC_7M25000038.pdf'                           | ''               | ''            | ''     | ''  | ''         | ''      | '20191022'
 '25MHZ'    | 'SMLF'    | 'EMPTY'  | 'BG6250000E0'(!)  = ''              | ''             | 'BG6250000E0'     |'X_7MXA'| ''          | 'XTAL SMD 25MHZ (20PF,10PPM)7M25000038'    | 'TXC'   | '7M25000038'                           | 'EP(V1)'     | ''        | 'IO'  | ''      | 'F0G-BELL'       | 'TXC_7M25000038.pdf'                           | ''               | ''            | ''     | ''  | ''         | ''      | '20191022'
 '24MHZ'    | 'SMLF'    | 'MISC'   | 'BG6240000G4'(!)  = ''              | ''             | 'BG6240000G4'     |'X_4S_X1E000021069700_3-2X2-5'| ''          | 'XTAL SMD 24MHZ(16PF,10PPM)X1E00002101300' | 'SEG'   | 'X1E000021013000'                      | 'EP(V1)'     | 'EP(V1)'  | 'IO'  | ''      | 'S8A-LOUIS'      | 'SEG_X1E000021013000.pdf'                      | ''               | ''            | ''     | ''  | ''         | ''      | '20200603'
 '24MHZ'    | 'SMLF'    | 'EMPTY'  | 'BG6240000G4'(!)  = ''              | ''             | 'BG6240000G4'     |'X_4S_X1E000021069700_3-2X2-5'| ''          | 'XTAL SMD 24MHZ(16PF,10PPM)X1E00002101300' | 'SEG'   | 'X1E000021013000'                      | 'EP(V1)'     | 'EP(V1)'  | 'IO'  | ''      | 'S8A-LOUIS'      | 'SEG_X1E000021013000.pdf'                      | ''               | ''            | ''     | ''  | ''         | ''      | '20200603'
 '48MHZ'    | 'SMLF'    | 'MISC'   | 'BG648000076'(!)  = ''              | ''             | 'BG648000076'     |'X_4S_FL4000120_3-2X2-5'| ''          | 'XTAL SMD 48MHZ(10PPM, 12PF)FL4800106'     | 'DDS'   | 'FL4800106'                            | 'EP(V1)'     | 'EP(V1)'  | 'IO'  | ''      | 'T6UB-MC'        | 'DDS_FL4800106.pdf'                            | ''               | ''            | ''     | ''  | ''         | ''      | '20200831'
 '48MHZ'    | 'SMLF'    | 'EMPTY'  | 'BG648000076'(!)  = ''              | ''             | 'BG648000076'     |'X_4S_FL4000120_3-2X2-5'| ''          | 'XTAL SMD 48MHZ(10PPM, 12PF)FL4800106'     | 'DDS'   | 'FL4800106'                            | 'EP(V1)'     | 'EP(V1)'  | 'IO'  | ''      | 'T6UB-MC'        | 'DDS_FL4800106.pdf'                            | ''               | ''            | ''     | ''  | ''         | ''      | '20200831'
 '25MHZ'    | 'SMLF'    | 'MISC'   | 'BG6250000I0'(!)  = ''              | ''             | 'BG6250000I0'     |'X_4S_FL4000120_3-2X2-5'| ''          | 'XTAL SMD 25MHZ(+-10PPM,12PF)FL2500350'    | 'DDS'   | 'FL2500350'                            | 'EP(V1)'     | 'EP(V1)'  | 'IO'  | ''      | 'F0C-GARY'       | 'DDS_FL2500350.pdf'                            | ''               | ''            | ''     | ''  | ''         | ''      | '20200921'
 '25MHZ'    | 'SMLF'    | 'EMPTY'  | 'BG6250000I0'(!)  = ''              | ''             | 'BG6250000I0'     |'X_4S_FL4000120_3-2X2-5'| ''          | 'XTAL SMD 25MHZ(+-10PPM,12PF)FL2500350'    | 'DDS'   | 'FL2500350'                            | 'EP(V1)'     | 'EP(V1)'  | 'IO'  | ''      | 'F0C-GARY'       | 'DDS_FL2500350.pdf'                            | ''               | ''            | ''     | ''  | ''         | ''      | '20200921'
 '25MHZ'    | 'SMLF'    | 'MISC'   | 'BG625000188'(!)  = ''              | ''             | 'BG625000188'     |'X_4S_FL4000120_3-2X2-5'| ''          | 'XTAL SMD 25MHZ(12PF,25PPM)FL2500221'      | 'ERC'   | 'FL2500221'                            | 'EP(V1)'     | 'EP(V1)'  | 'IO'  | ''      | 'F0CE-TONY'      | 'ERC_FL2500221.pdf'                            | ''               | ''            | ''     | ''  | ''         | ''      | '20201127'
 '25MHZ'    | 'SMLF'    | 'EMPTY'  | 'BG625000188'(!)  = ''              | ''             | 'BG625000188'     |'X_4S_FL4000120_3-2X2-5'| ''          | 'XTAL SMD 25MHZ(12PF,25PPM)FL2500221'      | 'ERC'   | 'FL2500221'                            | 'EP(V1)'     | 'EP(V1)'  | 'IO'  | ''      | 'F0CE-TONY'      | 'ERC_FL2500221.pdf'                            | ''               | ''            | ''     | ''  | ''         | ''      | '20201127'
 '25MHZ'    | 'SMLF'    | 'MISC'   | 'BG6250000I2'(!)  = ''              | ''             | 'BG6250000I2'     |'OSC4_E3FB'| ''          | 'XTAL 25MHZ(+-10PPM,12PF)E3SB25E000010E'   | 'HHE'   | 'E3SB25E000010E'                       | 'EP(V1)'     | 'EP(V1)'  | 'IO'  | ''      | 'F0CE-TONY'      | 'HHE_E3SB25E000010E.pdf'                       | ''               | ''            | ''     | ''  | ''         | ''      | '20201127'
 '25MHZ'    | 'SMLF'    | 'EMPTY'  | 'BG6250000I2'(!)  = ''              | ''             | 'BG6250000I2'     |'OSC4_E3FB'| ''          | 'XTAL 25MHZ(+-10PPM,12PF)E3SB25E000010E'   | 'HHE'   | 'E3SB25E000010E'                       | 'EP(V1)'     | 'EP(V1)'  | 'IO'  | ''      | 'F0CE-TONY'      | 'HHE_E3SB25E000010E.pdf'                       | ''               | ''            | ''     | ''  | ''         | ''      | '20201127'
 '26MHZ'    | 'SMLF'    | 'MISC'   | 'BG626000049'(!)  = ''              | ''             | 'BG626000049'     |'X_4S_8Z25000020_2-5X2'| ''          | 'XTAL 26MHZ(10PPM,11PF)8Z26000054'         | 'TXC'   | '8Z26000054'                           | 'EP(V1)'     | 'EP(V1)'  | 'IO'  | ''      | 'S6Z-TOM'        | 'TXC_8Z26000054.pdf'                           | ''               | ''            | ''     | ''  | ''         | ''      | '20210222'
 '26MHZ'    | 'SMLF'    | 'EMPTY'  | 'BG626000049'(!)  = ''              | ''             | 'BG626000049'     |'X_4S_8Z25000020_2-5X2'| ''          | 'XTAL 26MHZ(10PPM,11PF)8Z26000054'         | 'TXC'   | '8Z26000054'                           | 'EP(V1)'     | 'EP(V1)'  | 'IO'  | ''      | 'S6Z-TOM'        | 'TXC_8Z26000054.pdf'                           | ''               | ''            | ''     | ''  | ''         | ''      | '20210222'
 '25MHZ'    | 'SMLF'    | 'MISC'   | 'BG625000171'(!)  = ''              | ''             | 'BG625000171'     |'OSC4_E3FB'| ''          | 'XTAL SMD 25MHZ(10PPM,20PF)E3SB25E000040E' | 'HHE'   | 'E3SB25E000040E'                       | 'EP(V1)'     | 'EP(V1)'  | 'IO'  | ''      | 'T6U-JEFF'       | 'HHE_E3SB25E000040E.pdf'                       | ''               | ''            | ''     | ''  | ''         | ''      | '20210304'
 '25MHZ'    | 'SMLF'    | 'EMPTY'  | 'BG625000171'(!)  = ''              | ''             | 'BG625000171'     |'OSC4_E3FB'| ''          | 'XTAL SMD 25MHZ(10PPM,20PF)E3SB25E000040E' | 'HHE'   | 'E3SB25E000040E'                       | 'EP(V1)'     | 'EP(V1)'  | 'IO'  | ''      | 'T6U-JEFF'       | 'HHE_E3SB25E000040E.pdf'                       | ''               | ''            | ''     | ''  | ''         | ''      | '20210304'
 '25MHZ'    | 'SMLF'    | 'MISC'   | 'BG625000225'(!)  = ''              | ''             | 'BG625000225'     |'X_4S_FL4000120_3-2X2-5'| ''          | 'XTAL SMD 25MHZ(10PPM,10PF)FL2500462'      | 'DDS'   | 'FL2500462'                            | 'EP(V1)'     | 'EP(V1)'  | 'IO'  | ''      | 'S8Z-JACK'       | 'DDS_FL2500462.pdf'                            | ''               | ''            | ''     | ''  | ''         | ''      | '20210922'
 '25MHZ'    | 'SMLF'    | 'EMPTY'  | 'BG625000225'(!)  = ''              | ''             | 'BG625000225'     |'X_4S_FL4000120_3-2X2-5'| ''          | 'XTAL SMD 25MHZ(10PPM,10PF)FL2500462'      | 'DDS'   | 'FL2500462'                            | 'EP(V1)'     | 'EP(V1)'  | 'IO'  | ''      | 'S8Z-JACK'       | 'DDS_FL2500462.pdf'                            | ''               | ''            | ''     | ''  | ''         | ''      | '20210922'
 '48MHZ'    | 'SMLF'    | 'MISC'   | 'BG648000096'(!)  = ''              | ''             | 'BG648000096'     |'X_4S_7M25000083_3-2X2-5'| ''          | 'XTAL SMD 48MHZ(10PPM,8PF)7M48072002'      | 'TXC'   | '7M48072002'                           | 'EP(V1)'     | 'EP(V1)'  | 'IO'  | ''      | 'S3B-CLAIRE'     | 'TXC_7M48072002.pdf'                           | ''               | ''            | ''     | ''  | ''         | ''      | '20210922'
 '48MHZ'    | 'SMLF'    | 'EMPTY'  | 'BG648000096'(!)  = ''              | ''             | 'BG648000096'     |'X_4S_7M25000083_3-2X2-5'| ''          | 'XTAL SMD 48MHZ(10PPM,8PF)7M48072002'      | 'TXC'   | '7M48072002'                           | 'EP(V1)'     | 'EP(V1)'  | 'IO'  | ''      | 'S3B-CLAIRE'     | 'TXC_7M48072002.pdf'                           | ''               | ''            | ''     | ''  | ''         | ''      | '20210922'
 '48MHZ'    | 'SMLF'    | 'MISC'   | 'BG648000085'(!)  = ''              | ''             | 'BG648000085'     |'X_4S_X1E000021069700_3-2X2-5'| ''          | 'XTAL SMD 48MHZ(10PPM,8PF)X1E0000211114'   | 'SEG'   | 'X1E000021111400'                      | 'EP(V1)'     | 'EP(V1)'  | 'IO'  | ''      | 'S3B-CLAIRE'     | 'SEG_X1E000021111400.pdf'                      | ''               | ''            | ''     | ''  | ''         | ''      | '20210923'
 '48MHZ'    | 'SMLF'    | 'EMPTY'  | 'BG648000085'(!)  = ''              | ''             | 'BG648000085'     |'X_4S_X1E000021069700_3-2X2-5'| ''          | 'XTAL SMD 48MHZ(10PPM,8PF)X1E0000211114'   | 'SEG'   | 'X1E000021111400'                      | 'EP(V1)'     | 'EP(V1)'  | 'IO'  | ''      | 'S3B-CLAIRE'     | 'SEG_X1E000021111400.pdf'                      | ''               | ''            | ''     | ''  | ''         | ''      | '20210923'
 '12MHZ'    | 'SMLF'    | 'MISC'   | 'BG6120000E0'(!)  = ''              | ''             | 'BG6120000E0'     |'OSC4_DNCA250000ETS_2-5X2_H26'| ''          | 'XTAL 12MHZ(+-20PPM,10PF)E2SB12E00000EE'   | 'HHE'   | 'E2SB12E00000EE'                       | 'EP(V1)'     | 'EP(V1)'  | 'IO'  | ''      | 'F0T-IVES'       | 'HHE_E2SB12E00000EE.pdf'                       | ''               | ''            | ''     | ''  | ''         | ''      | '20211029'
 '12MHZ'    | 'SMLF'    | 'EMPTY'  | 'BG6120000E0'(!)  = ''              | ''             | 'BG6120000E0'     |'OSC4_DNCA250000ETS_2-5X2_H26'| ''          | 'XTAL 12MHZ(+-20PPM,10PF)E2SB12E00000EE'   | 'HHE'   | 'E2SB12E00000EE'                       | 'EP(V1)'     | 'EP(V1)'  | 'IO'  | ''      | 'F0T-IVES'       | 'HHE_E2SB12E00000EE.pdf'                       | ''               | ''            | ''     | ''  | ''         | ''      | '20211029'
 '25MHZ'    | 'SMLF'    | 'MISC'   | 'BG6250000G6'(!)  = ''              | ''             | 'BG6250000G6'     |'X_4S_7M25000083_3-2X2-5'| ''          | 'XTAL SMD 25MHZ(+-30PPM,18PF)7M25020018'   | 'TXC'   | '7M25020018'                           | 'EP(V1)'     | 'EP(V1)'  | 'IO'  | ''      | 'S3B-BERNIE'     | 'TXC_7M25020018.pdf'                           | ''               | ''            | ''     | ''  | ''         | ''      | '20211118'
 '25MHZ'    | 'SMLF'    | 'EMPTY'  | 'BG6250000G6'(!)  = ''              | ''             | 'BG6250000G6'     |'X_4S_7M25000083_3-2X2-5'| ''          | 'XTAL SMD 25MHZ(+-30PPM,18PF)7M25020018'   | 'TXC'   | '7M25020018'                           | 'EP(V1)'     | 'EP(V1)'  | 'IO'  | ''      | 'S3B-BERNIE'     | 'TXC_7M25020018.pdf'                           | ''               | ''            | ''     | ''  | ''         | ''      | '20211118'
 '25MHZ'    | 'SMLF'    | 'MISC'   | 'BG6250000F0'(!)  = ''              | ''             | 'BG6250000F0'     |'X_4S_FL4000120_3-2X2-5'| ''          | 'XTAL SMD 25MHZ(+-10PPM,8PF)FL2500498'     | 'DDS'   | 'FL2500498'                            | 'EP(V1)'     | 'EP(V1)'  | 'IO'  | ''      | 'F0C-IVES'       | 'DDS_FL2500498.pdf'                            | ''               | ''            | ''     | ''  | ''         | ''      | '20211129'
 '25MHZ'    | 'SMLF'    | 'EMPTY'  | 'BG6250000F0'(!)  = ''              | ''             | 'BG6250000F0'     |'X_4S_FL4000120_3-2X2-5'| ''          | 'XTAL SMD 25MHZ(+-10PPM,8PF)FL2500498'     | 'DDS'   | 'FL2500498'                            | 'EP(V1)'     | 'EP(V1)'  | 'IO'  | ''      | 'F0C-IVES'       | 'DDS_FL2500498.pdf'                            | ''               | ''            | ''     | ''  | ''         | ''      | '20211129'
 '12MHZ'    | 'SMLF'    | 'MISC'   | 'BG6120000A5'(!)  = 'End of Design' | 'Comp-Approve' | 'BG6120000A5'     |'X_4S_FY2500111'| ''          | 'CRYSTAL SMD 12MHZ(+-10PPM,18PF)FY1200112' | 'ERC'   | 'FY1200112'                            | 'EP(V1)'     | 'EP(V1)'  | 'IO'  | ''      | 'T2M-MICHAEL'    | 'ERC_FY1200112.pdf'                            | ''               | ''            | ''     | ''  | ''         | ''      | '20220222'
 '12MHZ'    | 'SMLF'    | 'EMPTY'  | 'BG6120000A5'(!)  = 'End of Design' | 'Comp-Approve' | 'BG6120000A5'     |'X_4S_FY2500111'| ''          | 'CRYSTAL SMD 12MHZ(+-10PPM,18PF)FY1200112' | 'ERC'   | 'FY1200112'                            | 'EP(V1)'     | 'EP(V1)'  | 'IO'  | ''      | 'T2M-MICHAEL'    | 'ERC_FY1200112.pdf'                            | ''               | ''            | ''     | ''  | ''         | ''      | '20220222'
 '12MHZ'    | 'SMLF'    | 'MISC'   | 'BG612000104'(!)  = ''              | ''             | 'BG612000104'     |'X_7MXA'| ''          | 'XTAL SMD 12MHZ(+-20PPM,18PF)7M12020002'   | 'TXC'   | '7M12020002'                           | 'EP(V1)'     | 'EP(V1)'  | 'IO'  | ''      | 'T6U-STAN'       | 'TXC_7M12020002.pdf'                           | ''               | ''            | ''     | ''  | ''         | ''      | '20220225'
 '12MHZ'    | 'SMLF'    | 'EMPTY'  | 'BG612000104'(!)  = ''              | ''             | 'BG612000104'     |'X_7MXA'| ''          | 'XTAL SMD 12MHZ(+-20PPM,18PF)7M12020002'   | 'TXC'   | '7M12020002'                           | 'EP(V1)'     | 'EP(V1)'  | 'IO'  | ''      | 'T6U-STAN'       | 'TXC_7M12020002.pdf'                           | ''               | ''            | ''     | ''  | ''         | ''      | '20220225'
 '50MHZ'    | 'SMLF'    | 'MISC'   | 'BG650000045'(!)  = ''              | ''             | 'BG650000045'     |'X_4S_FL4000120_3-2X2-5'| ''          | 'XTAL SMD 50 MHZ(+-10PPM,10PF)FL5000149'   | 'DDS'   | 'FL5000149'                            | 'EP(V1)'     | ''        | 'IO'  | ''      | 'S7P-JIM'        | 'DDS_FL5000149.pdf'                            | ''               | ''            | ''     | ''  | ''         | ''      | '20220506'
 '50MHZ'    | 'SMLF'    | 'EMPTY'  | 'BG650000045'(!)  = ''              | ''             | 'BG650000045'     |'X_4S_FL4000120_3-2X2-5'| ''          | 'XTAL SMD 50 MHZ(+-10PPM,10PF)FL5000149'   | 'DDS'   | 'FL5000149'                            | 'EP(V1)'     | ''        | 'IO'  | ''      | 'S7P-JIM'        | 'DDS_FL5000149.pdf'                            | ''               | ''            | ''     | ''  | ''         | ''      | '20220506'
 '25MHZ'    | 'SMLF'    | 'MISC'   | 'BG6250000P6'(!)  = ''              | ''             | 'BG6250000P6'     |'X_4S_FA-128_2X1-6'| ''          | 'XTAL SMD 25 MHZ(+-30PPM,12PF)FA-128'      | 'SEG'   | 'FA-128 25.000000 MHZ 12.0 +30.0-30.0' | 'EP(V1)'     | ''        | 'IO'  | ''      | 'S8A-JOSH'       | 'SEG_FA-128 25.000000 MHz 12.0 +30.0-30.0.pdf' | ''               | ''            | ''     | ''  | ''         | ''      | '20220512'
 '25MHZ'    | 'SMLF'    | 'EMPTY'  | 'BG6250000P6'(!)  = ''              | ''             | 'BG6250000P6'     |'X_4S_FA-128_2X1-6'| ''          | 'XTAL SMD 25 MHZ(+-30PPM,12PF)FA-128'      | 'SEG'   | 'FA-128 25.000000 MHZ 12.0 +30.0-30.0' | 'EP(V1)'     | ''        | 'IO'  | ''      | 'S8A-JOSH'       | 'SEG_FA-128 25.000000 MHz 12.0 +30.0-30.0.pdf' | ''               | ''            | ''     | ''  | ''         | ''      | '20220512'
 '25MHZ'    | 'SMLF'    | 'MISC'   | 'BG6250000P3'(!)  = ''              | ''             | 'BG6250000P3'     |'X_4S_8Z25000020_2-5X2'| ''          | 'XTAL SMD 25 MHZ(+-30PPM,8PF)8Z25070018'   | 'TXC'   | '8Z25070018'                           | 'EP(V1)'     | ''        | 'IO'  | ''      | 'S7P-JIM'        | 'TXC_8Z25070018.pdf'                           | ''               | ''            | ''     | ''  | ''         | ''      | '20220510'
 '25MHZ'    | 'SMLF'    | 'EMPTY'  | 'BG6250000P3'(!)  = ''              | ''             | 'BG6250000P3'     |'X_4S_8Z25000020_2-5X2'| ''          | 'XTAL SMD 25 MHZ(+-30PPM,8PF)8Z25070018'   | 'TXC'   | '8Z25070018'                           | 'EP(V1)'     | ''        | 'IO'  | ''      | 'S7P-JIM'        | 'TXC_8Z25070018.pdf'                           | ''               | ''            | ''     | ''  | ''         | ''      | '20220510'
 '25MHZ'    | 'SMLF'    | 'MISC'   | 'BG6250000P1'(!)  = ''              | ''             | 'BG6250000P1'     |'X_4S_FA-128_2X1-6'| ''          | 'XTAL SMD 25 MHZ(+-10PPM,12PF)FA-128 25.0' | 'SEG'   | 'FA-128 25.000000 MHZ 12.0 +10.0-10.0' | 'EP(V1)'     | ''        | 'IO'  | ''      | 'MF6-JOSH'       | 'SEG_FA-128 25.000000 MHZ 12.0 +10.0-10.0.pdf' | ''               | ''            | ''     | ''  | ''         | ''      | '20220613'
 '25MHZ'    | 'SMLF'    | 'EMPTY'  | 'BG6250000P1'(!)  = ''              | ''             | 'BG6250000P1'     |'X_4S_FA-128_2X1-6'| ''          | 'XTAL SMD 25 MHZ(+-10PPM,12PF)FA-128 25.0' | 'SEG'   | 'FA-128 25.000000 MHZ 12.0 +10.0-10.0' | 'EP(V1)'     | ''        | 'IO'  | ''      | 'MF6-JOSH'       | 'SEG_FA-128 25.000000 MHZ 12.0 +10.0-10.0.pdf' | ''               | ''            | ''     | ''  | ''         | ''      | '20220613'
 '12MHZ'    | 'SMLF'    | 'MISC'   | 'BG6120000B0'(!)  = ''              | ''             | 'BG6120000B0'     |'X_4S_8Z25000020_2-5X2'| ''          | 'XTAL 12MHZ(+-20PPM,10PF)8Z12000006'       | 'TXC'   | '8Z12000006'                           | 'EP(V1)'     | 'EP(V1)'  | 'IO'  | ''      | 'F0TG-CART'      | 'TXC_8Z12000006.pdf'                           | '8Z12000006.msg' | ''            | ''     | ''  | ''         | ''      | '20220617'
 '12MHZ'    | 'SMLF'    | 'EMPTY'  | 'BG6120000B0'(!)  = ''              | ''             | 'BG6120000B0'     |'X_4S_8Z25000020_2-5X2'| ''          | 'XTAL 12MHZ(+-20PPM,10PF)8Z12000006'       | 'TXC'   | '8Z12000006'                           | 'EP(V1)'     | 'EP(V1)'  | 'IO'  | ''      | 'F0TG-CART'      | 'TXC_8Z12000006.pdf'                           | '8Z12000006.msg' | ''            | ''     | ''  | ''         | ''      | '20220617'
 '12MHZ'    | 'SMLF'    | 'MISC'   | 'BG6120000D3'(!)  = ''              | ''             | 'BG6120000D3'     |'X_4S_FL4000120_3-2X2-5'| ''          | 'XTAL SMD 12MHZ(+-10PPM,10PF)FL1200185'    | 'DDS'   | 'FL1200185'                            | 'EP(V1)'     | 'EP(V1)'  | 'IO'  | ''      | 'S3IS-VINCENT'   | 'DDS_FL1200185.pdf'                            | ''               | ''            | ''     | ''  | ''         | ''      | '20220620'
 '12MHZ'    | 'SMLF'    | 'EMPTY'  | 'BG6120000D3'(!)  = ''              | ''             | 'BG6120000D3'     |'X_4S_FL4000120_3-2X2-5'| ''          | 'XTAL SMD 12MHZ(+-10PPM,10PF)FL1200185'    | 'DDS'   | 'FL1200185'                            | 'EP(V1)'     | 'EP(V1)'  | 'IO'  | ''      | 'S3IS-VINCENT'   | 'DDS_FL1200185.pdf'                            | ''               | ''            | ''     | ''  | ''         | ''      | '20220620'
 '25MHZ'    | 'SMLF'    | 'MISC'   | 'BG6250000Q5'(!)  = ''              | ''             | 'BG6250000Q5'     |'X_4S_8Z25000020_2-5X2'| ''          | 'XTAL SMD 25MHZ(8PF,20PPM)8Z25070026'      | 'TXC'   | '8Z25070026'                           | 'EP(V1)'     | ''        | 'IO'  | ''      | 'S3I-NICK'       | 'TXC_8Z25070026.pdf'                           | '8Z25070026.msg' | ''            | ''     | ''  | ''         | ''      | '20220630'
 '25MHZ'    | 'SMLF'    | 'EMPTY'  | 'BG6250000Q5'(!)  = ''              | ''             | 'BG6250000Q5'     |'X_4S_8Z25000020_2-5X2'| ''          | 'XTAL SMD 25MHZ(8PF,20PPM)8Z25070026'      | 'TXC'   | '8Z25070026'                           | 'EP(V1)'     | ''        | 'IO'  | ''      | 'S3I-NICK'       | 'TXC_8Z25070026.pdf'                           | '8Z25070026.msg' | ''            | ''     | ''  | ''         | ''      | '20220630'
 '25MHZ'    | 'SMLF'    | 'MISC'   | 'BG6250000Q6'(!)  = ''              | ''             | 'BG6250000Q6'     |'X_4S_7M25000083_3-2X2-5'| ''          | 'XTAL SMD 25MHZ(10PF,20PPM)7M25000149'     | 'TXC'   | '7M25000149'                           | 'EP(V1)'     | ''        | 'IO'  | ''      | 'S3I-NICK'       | 'TXC_7M25000149.pdf'                           | '7M25000149.msg' | ''            | ''     | ''  | ''         | ''      | '20220630'
 '25MHZ'    | 'SMLF'    | 'EMPTY'  | 'BG6250000Q6'(!)  = ''              | ''             | 'BG6250000Q6'     |'X_4S_7M25000083_3-2X2-5'| ''          | 'XTAL SMD 25MHZ(10PF,20PPM)7M25000149'     | 'TXC'   | '7M25000149'                           | 'EP(V1)'     | ''        | 'IO'  | ''      | 'S3I-NICK'       | 'TXC_7M25000149.pdf'                           | '7M25000149.msg' | ''            | ''     | ''  | ''         | ''      | '20220630'
 '27MHZ'    | 'SMLF'    | 'MISC'   | 'BG627000012'(!)  = ''              | ''             | 'BG627000012'     |'X_4S_7M25000083_3-2X2-5'| ''          | 'XTAL SMD 27MHZ(+-10PPM,10PF)7M27000008'   | 'TXC'   | '7M27000008'                           | 'EP'         | 'EP'      | 'IO'  | ''      | 'S7G-LINK'       | 'TXC_7M27000008.pdf'                           | '7M27000008.msg' | ''            | ''     | ''  | ''         | ''      | '20221129'
 '27MHZ'    | 'SMLF'    | 'EMPTY'  | 'BG627000012'(!)  = ''              | ''             | 'BG627000012'     |'X_4S_7M25000083_3-2X2-5'| ''          | 'XTAL SMD 27MHZ(+-10PPM,10PF)7M27000008'   | 'TXC'   | '7M27000008'                           | 'EP'         | 'EP'      | 'IO'  | ''      | 'S7G-LINK'       | 'TXC_7M27000008.pdf'                           | '7M27000008.msg' | ''            | ''     | ''  | ''         | ''      | '20221129'
 '20MHZ'    | 'SMLF'    | 'MISC'   | 'BG620000024'(!)  = ''              | ''             | 'BG620000024'     |'X_4S_8Y40000010_2X1-6'| ''          | 'CRYSTAL SMD 20MHZ(+-10PPM,16PF)'          | 'TXC'   | '8Y20000005'                           | 'EP(V1)'     | ''        | 'IO'  | ''      | 'S7M-STEVE'      | 'TXC_8Y20000005.pdf'                           | ''               | ''            | ''     | ''  | ''         | ''      | '20221205'
 '20MHZ'    | 'SMLF'    | 'EMPTY'  | 'BG620000024'(!)  = ''              | ''             | 'BG620000024'     |'X_4S_8Y40000010_2X1-6'| ''          | 'CRYSTAL SMD 20MHZ(+-10PPM,16PF)'          | 'TXC'   | '8Y20000005'                           | 'EP(V1)'     | ''        | 'IO'  | ''      | 'S7M-STEVE'      | 'TXC_8Y20000005.pdf'                           | ''               | ''            | ''     | ''  | ''         | ''      | '20221205'
 '25MHZ'    | 'SMLF'    | 'MISC'   | 'BG6250000L4'(!)  = ''              | ''             | 'BG6250000L4'     |'OSC4_E3FB'| ''          | 'XTAL SMD 25MHZ(+-10PPM,8PF)E3SB25E000004' | 'HHE'   | 'E3SB25E000004E'                       | 'EP(V1)'     | 'EP(V1)'  | 'IO'  | ''      | 'F0TG-CART'      | 'HHE_E3SB25E000004E.pdf'                       | ''               | ''            | ''     | ''  | ''         | ''      | '20221226'
 '25MHZ'    | 'SMLF'    | 'EMPTY'  | 'BG6250000L4'(!)  = ''              | ''             | 'BG6250000L4'     |'OSC4_E3FB'| ''          | 'XTAL SMD 25MHZ(+-10PPM,8PF)E3SB25E000004' | 'HHE'   | 'E3SB25E000004E'                       | 'EP(V1)'     | 'EP(V1)'  | 'IO'  | ''      | 'F0TG-CART'      | 'HHE_E3SB25E000004E.pdf'                       | ''               | ''            | ''     | ''  | ''         | ''      | '20221226'
 '24MHZ'    | 'SMLF'    | 'MISC'   | 'BG6240000L9'(!)  = ''              | ''             | 'BG6240000L9'     |'X_4S_FL4000120_3-2X2-5'| ''          | 'XTAL SMD 24MHZ(+-30PPM,20PF)FL2400040'    | 'DDS'   | 'FL2400040'                            | 'EP(V1)'     | ''        | 'IO'  | ''      | 'F0EG-PATRICK'   | 'DDS_FL2400040.pdf'                            | ''               | ''            | ''     | ''  | ''         | ''      | '20230209'
 '24MHZ'    | 'SMLF'    | 'EMPTY'  | 'BG6240000L9'(!)  = ''              | ''             | 'BG6240000L9'     |'X_4S_FL4000120_3-2X2-5'| ''          | 'XTAL SMD 24MHZ(+-30PPM,20PF)FL2400040'    | 'DDS'   | 'FL2400040'                            | 'EP(V1)'     | ''        | 'IO'  | ''      | 'F0EG-PATRICK'   | 'DDS_FL2400040.pdf'                            | ''               | ''            | ''     | ''  | ''         | ''      | '20230209'
 '24MHZ'    | 'SMLF'    | 'MISC'   | 'BG6240000G4SEL1'(!) = ''              | ''               | 'BG6240000G4SEL1' |'X_4S_X1E000021069700_3-2X2-5'| ''          | 'XTAL SMD 24MHZ(16PF,10PPM)X1E SELASN'     | 'SEG'   | 'X1E000021013000'                      | 'EP(V1)'     | 'EP(V1)'  | 'IO'  | ''      | 'S8A-LOUIS'      | 'SEG_X1E000021013000.pdf'                      | 'SEL_15QPN.xlsx' | ''            | ''     | ''  | ''         | ''      | '20230629'
 '24MHZ'    | 'SMLF'    | 'EMPTY'  | 'BG6240000G4SEL1'(!) = ''              | ''               | 'BG6240000G4SEL1' |'X_4S_X1E000021069700_3-2X2-5'| ''          | 'XTAL SMD 24MHZ(16PF,10PPM)X1E SELASN'     | 'SEG'   | 'X1E000021013000'                      | 'EP(V1)'     | 'EP(V1)'  | 'IO'  | ''      | 'S8A-LOUIS'      | 'SEG_X1E000021013000.pdf'                      | 'SEL_15QPN.xlsx' | ''            | ''     | ''  | ''         | ''      | '20230629'
 '25MHZ'    | 'SMLF'    | 'MISC'   | 'BG625000225SEL1'(!) = ''               | ''               | 'BG625000225SEL1' |'X_4S_FL4000120_3-2X2-5'| ''          | 'XTAL SMD 25MHZ(10PPM,10PF)FL25 SELASN'    | 'DDS'   | 'FL2500462'                            | 'EP(V1)'     | 'EP(V1)'  | 'IO'  | ''      | 'S8Z-JACK'       | 'DDS_FL2500462.pdf'                            | 'SEL_15QPN.xlsx' | ''            | ''     | ''  | ''         | ''      | '20230629'
 '25MHZ'    | 'SMLF'    | 'EMPTY'  | 'BG625000225SEL1'(!) = ''               | ''               | 'BG625000225SEL1' |'X_4S_FL4000120_3-2X2-5'| ''          | 'XTAL SMD 25MHZ(10PPM,10PF)FL25 SELASN'    | 'DDS'   | 'FL2500462'                            | 'EP(V1)'     | 'EP(V1)'  | 'IO'  | ''      | 'S8Z-JACK'       | 'DDS_FL2500462.pdf'                            | 'SEL_15QPN.xlsx' | ''            | ''     | ''  | ''         | ''      | '20230629'

END_PART

END.

